# T6G (Grand Teton) — schematic netlist excerpt (pin names and nets, part order shuffled) for the footprints in the layout excerpt that follows; sources: Cadence DE-HDL packaged netlist, KiCad conversion of 04192023_DAF0TMB3IC0_F0TG_MB_C_brd_V02_OCP.brd

PC6601  Q_CAP  0.1UF 25V 10% EMPTY  pkg 0402  page 362 : A = P0V9_RETIMER_CPU0_VMON ; B = GND
PC210_2  Q_CAP  1UF 25V 10% X6S  pkg C0402  page 208 : A = SW_P12V_AUX_PVDD11_S3_P0_FLT ; B = GND

(kicad_pcb
	(version 20260206)
	(generator "pcbnew")
	(generator_version "10.0")
	(general
		(thickness 1.6)
		(legacy_teardrops no)
	)
	(paper "A4")
	(title_block
		(title "04192023_DAF0TMB3IC0_F0TG_MB_C_brd_V02_OCP.brd")
		(comment 1 "Grand Teton / footprints 904-905 of 8354")
	)
	(layers
		(0 "F.Cu" signal "TOP")
		(4 "In1.Cu" signal "GND")
		(6 "In2.Cu" signal "IN1")
		(8 "In3.Cu" signal "GND1")
		(10 "In4.Cu" signal "IN2")
		(12 "In5.Cu" signal "GND2")
		(14 "In6.Cu" signal "IN3")
		(16 "In7.Cu" signal "GND3")
		(18 "In8.Cu" signal "VCC")
		(20 "In9.Cu" signal "VCC1")
		(22 "In10.Cu" signal "GND4")
		(24 "In11.Cu" signal "IN4")
		(26 "In12.Cu" signal "GND5")
		(28 "In13.Cu" signal "IN5")
		(30 "In14.Cu" signal "GND6")
		(32 "In15.Cu" signal "IN6")
		(34 "In16.Cu" signal "GND7")
		(2 "B.Cu" signal "BOTTOM")
		(9 "F.Adhes" user "F.Adhesive")
		(11 "B.Adhes" user "B.Adhesive")
		(13 "F.Paste" user "Package Geometry/Pastemask Top")
		(15 "B.Paste" user "Package Geometry/Pastemask Bottom")
		(5 "F.SilkS" user "Ref Des/Silkscreen Top")
		(7 "B.SilkS" user "Ref Des/Silkscreen Bottom")
		(1 "F.Mask" user "Board Geometry/Soldermask Top")
		(3 "B.Mask" user "Board Geometry/Soldermask Bottom")
		(17 "Dwgs.User" user "User.Drawings")
		(19 "Cmts.User" user "User.Comments")
		(21 "Eco1.User" user "User.Eco1")
		(23 "Eco2.User" user "User.Eco2")
		(25 "Edge.Cuts" user "Board Geometry/Outline")
		(27 "Margin" user)
		(31 "F.CrtYd" user "Package Geometry/Place Bound Top")
		(29 "B.CrtYd" user "Package Geometry/Place Bound Bottom")
		(35 "F.Fab" user "Ref Des/Assembly Top")
		(33 "B.Fab" user "Ref Des/Assembly Bottom")
	)
	(footprint ""
		(layer "F.Cu")
		(at 435.628288 -351.22866 -90)
		(property "Reference" "PC210_2"
			(at 0 0 270)
			(layer "F.SilkS")
			(hide yes)
			(effects
				(font
					(size 1.27 1.27)
				)
			)
		)
		(property "Value" ""
			(at 0 0 270)
			(layer "F.Fab")
			(effects
				(font
					(size 1.27 1.27)
				)
			)
		)
		(duplicate_pad_numbers_are_jumpers no)
		(fp_line
			(start -0.7874 0.4064)
			(end -0.7874 -0.4064)
			(stroke
				(width 0.1524)
				(type default)
			)
			(layer "F.SilkS")
		)
		(fp_line
			(start 0.7874 0.4064)
			(end -0.7874 0.4064)
			(stroke
				(width 0.1524)
				(type default)
			)
			(layer "F.SilkS")
		)
		(fp_line
			(start -0.7874 -0.4064)
			(end 0.7874 -0.4064)
			(stroke
				(width 0.1524)
				(type default)
			)
			(layer "F.SilkS")
		)
		(fp_line
			(start 0.7874 -0.4064)
			(end 0.7874 0.4064)
			(stroke
				(width 0.1524)
				(type default)
			)
			(layer "F.SilkS")
		)
		(fp_line
			(start -0.67945 0.3048)
			(end -0.67945 -0.305054)
			(stroke
				(width 0.1)
				(type default)
			)
			(layer "F.Fab")
		)
		(fp_line
			(start -0.12065 0.3048)
			(end -0.67945 0.3048)
			(stroke
				(width 0.1)
				(type default)
			)
			(layer "F.Fab")
		)
		(fp_line
			(start 0.120396 0.3048)
			(end 0.120396 0.2794)
			(stroke
				(width 0.1)
				(type default)
			)
			(layer "F.Fab")
		)
		(fp_line
			(start 0.67945 0.3048)
			(end 0.120396 0.3048)
			(stroke
				(width 0.1)
				(type default)
			)
			(layer "F.Fab")
		)
		(fp_line
			(start -0.12065 0.2794)
			(end -0.12065 0.3048)
			(stroke
				(width 0.1)
				(type default)
			)
			(layer "F.Fab")
		)
		(fp_line
			(start 0.120396 0.2794)
			(end -0.12065 0.2794)
			(stroke
				(width 0.1)
				(type default)
			)
			(layer "F.Fab")
		)
		(fp_line
			(start -0.12065 -0.2794)
			(end 0.12065 -0.2794)
			(stroke
				(width 0.1)
				(type default)
			)
			(layer "F.Fab")
		)
		(fp_line
			(start 0.12065 -0.2794)
			(end 0.12065 -0.3048)
			(stroke
				(width 0.1)
				(type default)
			)
			(layer "F.Fab")
		)
		(fp_line
			(start 0.12065 -0.3048)
			(end 0.67945 -0.3048)
			(stroke
				(width 0.1)
				(type default)
			)
			(layer "F.Fab")
		)
		(fp_line
			(start 0.67945 -0.3048)
			(end 0.67945 0.3048)
			(stroke
				(width 0.1)
				(type default)
			)
			(layer "F.Fab")
		)
		(fp_line
			(start -0.67945 -0.305054)
			(end -0.12065 -0.305054)
			(stroke
				(width 0.1)
				(type default)
			)
			(layer "F.Fab")
		)
		(fp_line
			(start -0.12065 -0.305054)
			(end -0.12065 -0.2794)
			(stroke
				(width 0.1)
				(type default)
			)
			(layer "F.Fab")
		)
		(pad "1" smd circle
			(at -0.40005 0 270)
			(size 0 0)
			(layers "F.Cu" "F.Mask" "F.Paste")
			(net "SW_P12V_AUX_PVDD11_S3_P0_FLT")
		)
		(pad "2" smd circle
			(at 0.40005 0 270)
			(size 0 0)
			(layers "F.Cu" "F.Mask" "F.Paste")
			(net "GND")
		)
	)
	(footprint ""
		(layer "F.Cu")
		(at 449.531232 -425.210478)
		(property "Reference" "PC6601"
			(at 0 0 0)
			(layer "F.SilkS")
			(hide yes)
			(effects
				(font
					(size 1.27 1.27)
				)
			)
		)
		(property "Value" ""
			(at 0 0 0)
			(layer "F.Fab")
			(effects
				(font
					(size 1.27 1.27)
				)
			)
		)
		(duplicate_pad_numbers_are_jumpers no)
		(fp_line
			(start -0.7874 -0.4064)
			(end 0.7874 -0.4064)
			(stroke
				(width 0.1524)
				(type default)
			)
			(layer "F.SilkS")
		)
		(fp_line
			(start -0.7874 0.4064)
			(end -0.7874 -0.4064)
			(stroke
				(width 0.1524)
				(type default)
			)
			(layer "F.SilkS")
		)
		(fp_line
			(start 0.7874 -0.4064)
			(end 0.7874 0.4064)
			(stroke
				(width 0.1524)
				(type default)
			)
			(layer "F.SilkS")
		)
		(fp_line
			(start 0.7874 0.4064)
			(end -0.7874 0.4064)
			(stroke
				(width 0.1524)
				(type default)
			)
			(layer "F.SilkS")
		)
		(fp_line
			(start -0.67945 -0.305054)
			(end -0.12065 -0.305054)
			(stroke
				(width 0.1)
				(type default)
			)
			(layer "F.Fab")
		)
		(fp_line
			(start -0.67945 0.3048)
			(end -0.67945 -0.305054)
			(stroke
				(width 0.1)
				(type default)
			)
			(layer "F.Fab")
		)
		(fp_line
			(start -0.12065 -0.305054)
			(end -0.12065 -0.2794)
			(stroke
				(width 0.1)
				(type default)
			)
			(layer "F.Fab")
		)
		(fp_line
			(start -0.12065 -0.2794)
			(end 0.12065 -0.2794)
			(stroke
				(width 0.1)
				(type default)
			)
			(layer "F.Fab")
		)
		(fp_line
			(start -0.12065 0.2794)
			(end -0.12065 0.3048)
			(stroke
				(width 0.1)
				(type default)
			)
			(layer "F.Fab")
		)
		(fp_line
			(start -0.12065 0.3048)
			(end -0.67945 0.3048)
			(stroke
				(width 0.1)
				(type default)
			)
			(layer "F.Fab")
		)
		(fp_line
			(start 0.120396 0.2794)
			(end -0.12065 0.2794)
			(stroke
				(width 0.1)
				(type default)
			)
			(layer "F.Fab")
		)
		(fp_line
			(start 0.120396 0.3048)
			(end 0.120396 0.2794)
			(stroke
				(width 0.1)
				(type default)
			)
			(layer "F.Fab")
		)
		(fp_line
			(start 0.12065 -0.3048)
			(end 0.67945 -0.3048)
			(stroke
				(width 0.1)
				(type default)
			)
			(layer "F.Fab")
		)
		(fp_line
			(start 0.12065 -0.2794)
			(end 0.12065 -0.3048)
			(stroke
				(width 0.1)
				(type default)
			)
			(layer "F.Fab")
		)
		(fp_line
			(start 0.67945 -0.3048)
			(end 0.67945 0.3048)
			(stroke
				(width 0.1)
				(type default)
			)
			(layer "F.Fab")
		)
		(fp_line
			(start 0.67945 0.3048)
			(end 0.120396 0.3048)
			(stroke
				(width 0.1)
				(type default)
			)
			(layer "F.Fab")
		)
		(pad "1" smd circle
			(at -0.40005 0)
			(size 0 0)
			(layers "F.Cu" "F.Mask" "F.Paste")
			(net "P0V9_RETIMER_CPU0_VMON")
		)
		(pad "2" smd circle
			(at 0.40005 0)
			(size 0 0)
			(layers "F.Cu" "F.Mask" "F.Paste")
			(net "GND")
		)
	)
)
